(kicad_pcb
	(version 20260206)
	(generator "pcbnew")
	(generator_version "10.0")
	(general
		(thickness 1.6)
		(legacy_teardrops no)
	)
	(paper "A4")
	(title_block
		(title "04192023_DAF0TMB3IC0_F0TG_MB_C_brd_V02_OCP.brd")
		(comment 1 "Grand Teton / footprint 4761 of 8354 (J18), pads 1-113 of 291")
	)
	(layers
		(0 "F.Cu" signal "TOP")
		(4 "In1.Cu" signal "GND")
		(6 "In2.Cu" signal "IN1")
		(8 "In3.Cu" signal "GND1")
		(10 "In4.Cu" signal "IN2")
		(12 "In5.Cu" signal "GND2")
		(14 "In6.Cu" signal "IN3")
		(16 "In7.Cu" signal "GND3")
		(18 "In8.Cu" signal "VCC")
		(20 "In9.Cu" signal "VCC1")
		(22 "In10.Cu" signal "GND4")
		(24 "In11.Cu" signal "IN4")
		(26 "In12.Cu" signal "GND5")
		(28 "In13.Cu" signal "IN5")
		(30 "In14.Cu" signal "GND6")
		(32 "In15.Cu" signal "IN6")
		(34 "In16.Cu" signal "GND7")
		(2 "B.Cu" signal "BOTTOM")
		(9 "F.Adhes" user "F.Adhesive")
		(11 "B.Adhes" user "B.Adhesive")
		(13 "F.Paste" user "Package Geometry/Pastemask Top")
		(15 "B.Paste" user "Package Geometry/Pastemask Bottom")
		(5 "F.SilkS" user "Ref Des/Silkscreen Top")
		(7 "B.SilkS" user "Ref Des/Silkscreen Bottom")
		(1 "F.Mask" user "Board Geometry/Soldermask Top")
		(3 "B.Mask" user "Board Geometry/Soldermask Bottom")
		(17 "Dwgs.User" user "User.Drawings")
		(19 "Cmts.User" user "User.Comments")
		(21 "Eco1.User" user "User.Eco1")
		(23 "Eco2.User" user "User.Eco2")
		(25 "Edge.Cuts" user "Board Geometry/Outline")
		(27 "Margin" user)
		(31 "F.CrtYd" user "Package Geometry/Place Bound Top")
		(29 "B.CrtYd" user "Package Geometry/Place Bound Bottom")
		(35 "F.Fab" user "Ref Des/Assembly Top")
		(33 "B.Fab" user "Ref Des/Assembly Bottom")
	)
	(footprint ""
		(layer "F.Cu")
		(at 429.506126 -255.560068 180)
		(property "Reference" "J18"
			(at 0.484632 -81.752948 0)
			(unlocked yes)
			(layer "F.SilkS")
			(effects
				(font
					(size 0.7874 0.5842)
					(thickness 0.1524)
				)
			)
		)
		(property "Value" ""
			(at 0 0 180)
			(layer "F.Fab")
			(effects
				(font
					(size 1.27 1.27)
				)
			)
		)
		(duplicate_pad_numbers_are_jumpers no)
		(pad "1" smd rect
			(at -2.050034 -63.324994 90)
			(size 0.519938 1.4986)
			(layers "F.Cu" "F.Mask" "F.Paste")
			(net "P12V_MEM_CPU0")
		)
		(pad "2" smd rect
			(at -2.050034 -62.47511 90)
			(size 0.519938 1.4986)
			(layers "F.Cu" "F.Mask" "F.Paste")
			(net "Net_2361")
		)
		(pad "3" smd rect
			(at -2.050034 -61.624972 90)
			(size 0.519938 1.4986)
			(layers "F.Cu" "F.Mask" "F.Paste")
			(net "P3V3_AUX")
		)
		(pad "4" smd rect
			(at -2.050034 -60.775088 90)
			(size 0.519938 1.4986)
			(layers "F.Cu" "F.Mask" "F.Paste")
			(net "I3C_SPD_DDRI_CPU0_SCL")
		)
		(pad "5" smd rect
			(at -2.050034 -59.92495 90)
			(size 0.519938 1.4986)
			(layers "F.Cu" "F.Mask" "F.Paste")
			(net "I3C_SPD_DDRI_CPU0_SDA")
		)
		(pad "6" smd rect
			(at -2.050034 -59.075066 90)
			(size 0.519938 1.4986)
			(layers "F.Cu" "F.Mask" "F.Paste")
			(net "GND")
		)
		(pad "7" smd rect
			(at -2.050034 -58.224928 90)
			(size 0.519938 1.4986)
			(layers "F.Cu" "F.Mask" "F.Paste")
			(net "M_I_CPU0_SA_DQ<0>")
		)
		(pad "8" smd rect
			(at -2.050034 -57.375044 90)
			(size 0.519938 1.4986)
			(layers "F.Cu" "F.Mask" "F.Paste")
			(net "GND")
		)
		(pad "9" smd rect
			(at -2.050034 -56.524906 90)
			(size 0.519938 1.4986)
			(layers "F.Cu" "F.Mask" "F.Paste")
			(net "M_I_CPU0_SA_DQ<1>")
		)
		(pad "10" smd rect
			(at -2.050034 -55.675022 90)
			(size 0.519938 1.4986)
			(layers "F.Cu" "F.Mask" "F.Paste")
			(net "GND")
		)
		(pad "11" smd rect
			(at -2.050034 -54.824884 90)
			(size 0.519938 1.4986)
			(layers "F.Cu" "F.Mask" "F.Paste")
			(net "M_I_CPU0_SA_DQS_DP<0>")
		)
		(pad "12" smd rect
			(at -2.050034 -53.975 90)
			(size 0.519938 1.4986)
			(layers "F.Cu" "F.Mask" "F.Paste")
			(net "M_I_CPU0_SA_DQS_DN<0>")
		)
		(pad "13" smd rect
			(at -2.050034 -53.125116 90)
			(size 0.519938 1.4986)
			(layers "F.Cu" "F.Mask" "F.Paste")
			(net "GND")
		)
		(pad "14" smd rect
			(at -2.050034 -52.274978 90)
			(size 0.519938 1.4986)
			(layers "F.Cu" "F.Mask" "F.Paste")
			(net "M_I_CPU0_SA_DQ<4>")
		)
		(pad "15" smd rect
			(at -2.050034 -51.425094 90)
			(size 0.519938 1.4986)
			(layers "F.Cu" "F.Mask" "F.Paste")
			(net "GND")
		)
		(pad "16" smd rect
			(at -2.050034 -50.574956 90)
			(size 0.519938 1.4986)
			(layers "F.Cu" "F.Mask" "F.Paste")
			(net "M_I_CPU0_SA_DQ<5>")
		)
		(pad "17" smd rect
			(at -2.050034 -49.725072 90)
			(size 0.519938 1.4986)
			(layers "F.Cu" "F.Mask" "F.Paste")
			(net "GND")
		)
		(pad "18" smd rect
			(at -2.050034 -48.874934 90)
			(size 0.519938 1.4986)
			(layers "F.Cu" "F.Mask" "F.Paste")
			(net "M_I_CPU0_SA_DQ<8>")
		)
		(pad "19" smd rect
			(at -2.050034 -48.02505 90)
			(size 0.519938 1.4986)
			(layers "F.Cu" "F.Mask" "F.Paste")
			(net "GND")
		)
		(pad "20" smd rect
			(at -2.050034 -47.174912 90)
			(size 0.519938 1.4986)
			(layers "F.Cu" "F.Mask" "F.Paste")
			(net "M_I_CPU0_SA_DQ<9>")
		)
		(pad "21" smd rect
			(at -2.050034 -46.325028 90)
			(size 0.519938 1.4986)
			(layers "F.Cu" "F.Mask" "F.Paste")
			(net "GND")
		)
		(pad "22" smd rect
			(at -2.050034 -45.47489 90)
			(size 0.519938 1.4986)
			(layers "F.Cu" "F.Mask" "F.Paste")
			(net "M_I_CPU0_SA_DQS_DP<1>")
		)
		(pad "23" smd rect
			(at -2.050034 -44.625006 90)
			(size 0.519938 1.4986)
			(layers "F.Cu" "F.Mask" "F.Paste")
			(net "M_I_CPU0_SA_DQS_DN<1>")
		)
		(pad "24" smd rect
			(at -2.050034 -43.775122 90)
			(size 0.519938 1.4986)
			(layers "F.Cu" "F.Mask" "F.Paste")
			(net "GND")
		)
		(pad "25" smd rect
			(at -2.050034 -42.924984 90)
			(size 0.519938 1.4986)
			(layers "F.Cu" "F.Mask" "F.Paste")
			(net "M_I_CPU0_SA_DQ<12>")
		)
		(pad "26" smd rect
			(at -2.050034 -42.0751 90)
			(size 0.519938 1.4986)
			(layers "F.Cu" "F.Mask" "F.Paste")
			(net "GND")
		)
		(pad "27" smd rect
			(at -2.050034 -41.224962 90)
			(size 0.519938 1.4986)
			(layers "F.Cu" "F.Mask" "F.Paste")
			(net "M_I_CPU0_SA_DQ<13>")
		)
		(pad "28" smd rect
			(at -2.050034 -40.375078 90)
			(size 0.519938 1.4986)
			(layers "F.Cu" "F.Mask" "F.Paste")
			(net "GND")
		)
		(pad "29" smd rect
			(at -2.050034 -39.52494 90)
			(size 0.519938 1.4986)
			(layers "F.Cu" "F.Mask" "F.Paste")
			(net "M_I_CPU0_SA_DQ<16>")
		)
		(pad "30" smd rect
			(at -2.050034 -38.675056 90)
			(size 0.519938 1.4986)
			(layers "F.Cu" "F.Mask" "F.Paste")
			(net "GND")
		)
		(pad "31" smd rect
			(at -2.050034 -37.824918 90)
			(size 0.519938 1.4986)
			(layers "F.Cu" "F.Mask" "F.Paste")
			(net "M_I_CPU0_SA_DQ<17>")
		)
		(pad "32" smd rect
			(at -2.050034 -36.975034 90)
			(size 0.519938 1.4986)
			(layers "F.Cu" "F.Mask" "F.Paste")
			(net "GND")
		)
		(pad "33" smd rect
			(at -2.050034 -36.124896 90)
			(size 0.519938 1.4986)
			(layers "F.Cu" "F.Mask" "F.Paste")
			(net "M_I_CPU0_SA_DQS_DP<2>")
		)
		(pad "34" smd rect
			(at -2.050034 -35.275012 90)
			(size 0.519938 1.4986)
			(layers "F.Cu" "F.Mask" "F.Paste")
			(net "M_I_CPU0_SA_DQS_DN<2>")
		)
		(pad "35" smd rect
			(at -2.050034 -34.425128 90)
			(size 0.519938 1.4986)
			(layers "F.Cu" "F.Mask" "F.Paste")
			(net "GND")
		)
		(pad "36" smd rect
			(at -2.050034 -33.57499 90)
			(size 0.519938 1.4986)
			(layers "F.Cu" "F.Mask" "F.Paste")
			(net "M_I_CPU0_SA_DQ<20>")
		)
		(pad "37" smd rect
			(at -2.050034 -32.725106 90)
			(size 0.519938 1.4986)
			(layers "F.Cu" "F.Mask" "F.Paste")
			(net "GND")
		)
		(pad "38" smd rect
			(at -2.050034 -31.874968 90)
			(size 0.519938 1.4986)
			(layers "F.Cu" "F.Mask" "F.Paste")
			(net "M_I_CPU0_SA_DQ<21>")
		)
		(pad "39" smd rect
			(at -2.050034 -31.025084 90)
			(size 0.519938 1.4986)
			(layers "F.Cu" "F.Mask" "F.Paste")
			(net "GND")
		)
		(pad "40" smd rect
			(at -2.050034 -30.174946 90)
			(size 0.519938 1.4986)
			(layers "F.Cu" "F.Mask" "F.Paste")
			(net "M_I_CPU0_SA_DQ<24>")
		)
		(pad "41" smd rect
			(at -2.050034 -29.325062 90)
			(size 0.519938 1.4986)
			(layers "F.Cu" "F.Mask" "F.Paste")
			(net "GND")
		)
		(pad "42" smd rect
			(at -2.050034 -28.474924 90)
			(size 0.519938 1.4986)
			(layers "F.Cu" "F.Mask" "F.Paste")
			(net "M_I_CPU0_SA_DQ<25>")
		)
		(pad "43" smd rect
			(at -2.050034 -27.62504 90)
			(size 0.519938 1.4986)
			(layers "F.Cu" "F.Mask" "F.Paste")
			(net "GND")
		)
		(pad "44" smd rect
			(at -2.050034 -26.774902 90)
			(size 0.519938 1.4986)
			(layers "F.Cu" "F.Mask" "F.Paste")
			(net "M_I_CPU0_SA_DQS_DP<3>")
		)
		(pad "45" smd rect
			(at -2.050034 -25.925018 90)
			(size 0.519938 1.4986)
			(layers "F.Cu" "F.Mask" "F.Paste")
			(net "M_I_CPU0_SA_DQS_DN<3>")
		)
		(pad "46" smd rect
			(at -2.050034 -25.07488 90)
			(size 0.519938 1.4986)
			(layers "F.Cu" "F.Mask" "F.Paste")
			(net "GND")
		)
		(pad "47" smd rect
			(at -2.050034 -24.224996 90)
			(size 0.519938 1.4986)
			(layers "F.Cu" "F.Mask" "F.Paste")
			(net "M_I_CPU0_SA_DQ<28>")
		)
		(pad "48" smd rect
			(at -2.050034 -23.375112 90)
			(size 0.519938 1.4986)
			(layers "F.Cu" "F.Mask" "F.Paste")
			(net "GND")
		)
		(pad "49" smd rect
			(at -2.050034 -22.524974 90)
			(size 0.519938 1.4986)
			(layers "F.Cu" "F.Mask" "F.Paste")
			(net "M_I_CPU0_SA_DQ<29>")
		)
		(pad "50" smd rect
			(at -2.050034 -21.67509 90)
			(size 0.519938 1.4986)
			(layers "F.Cu" "F.Mask" "F.Paste")
			(net "GND")
		)
		(pad "51" smd rect
			(at -2.050034 -20.824952 90)
			(size 0.519938 1.4986)
			(layers "F.Cu" "F.Mask" "F.Paste")
			(net "M_I_CPU0_SA_CB<0>")
		)
		(pad "52" smd rect
			(at -2.050034 -19.975068 90)
			(size 0.519938 1.4986)
			(layers "F.Cu" "F.Mask" "F.Paste")
			(net "GND")
		)
		(pad "53" smd rect
			(at -2.050034 -19.12493 90)
			(size 0.519938 1.4986)
			(layers "F.Cu" "F.Mask" "F.Paste")
			(net "M_I_CPU0_SA_CB<1>")
		)
		(pad "54" smd rect
			(at -2.050034 -18.275046 90)
			(size 0.519938 1.4986)
			(layers "F.Cu" "F.Mask" "F.Paste")
			(net "GND")
		)
		(pad "55" smd rect
			(at -2.050034 -17.424908 90)
			(size 0.519938 1.4986)
			(layers "F.Cu" "F.Mask" "F.Paste")
			(net "M_I_CPU0_SA_DQS_DP<4>")
		)
		(pad "56" smd rect
			(at -2.050034 -16.575024 90)
			(size 0.519938 1.4986)
			(layers "F.Cu" "F.Mask" "F.Paste")
			(net "M_I_CPU0_SA_DQS_DN<4>")
		)
		(pad "57" smd rect
			(at -2.050034 -15.724886 90)
			(size 0.519938 1.4986)
			(layers "F.Cu" "F.Mask" "F.Paste")
			(net "GND")
		)
		(pad "58" smd rect
			(at -2.050034 -14.875002 90)
			(size 0.519938 1.4986)
			(layers "F.Cu" "F.Mask" "F.Paste")
			(net "M_I_CPU0_SA_CB<4>")
		)
		(pad "59" smd rect
			(at -2.050034 -14.025118 90)
			(size 0.519938 1.4986)
			(layers "F.Cu" "F.Mask" "F.Paste")
			(net "GND")
		)
		(pad "60" smd rect
			(at -2.050034 -13.17498 90)
			(size 0.519938 1.4986)
			(layers "F.Cu" "F.Mask" "F.Paste")
			(net "M_I_CPU0_SA_CB<5>")
		)
		(pad "61" smd rect
			(at -2.050034 -12.325096 90)
			(size 0.519938 1.4986)
			(layers "F.Cu" "F.Mask" "F.Paste")
			(net "GND")
		)
		(pad "62" smd rect
			(at -2.050034 -11.474958 90)
			(size 0.519938 1.4986)
			(layers "F.Cu" "F.Mask" "F.Paste")
			(net "M_I_CPU0_ALERT_N")
		)
		(pad "63" smd rect
			(at -2.050034 -10.625074 90)
			(size 0.519938 1.4986)
			(layers "F.Cu" "F.Mask" "F.Paste")
			(net "GND")
		)
		(pad "64" smd rect
			(at -2.050034 -9.774936 90)
			(size 0.519938 1.4986)
			(layers "F.Cu" "F.Mask" "F.Paste")
			(net "M_I_CPU0_SA_CS_N<0>")
		)
		(pad "65" smd rect
			(at -2.050034 -8.925052 90)
			(size 0.519938 1.4986)
			(layers "F.Cu" "F.Mask" "F.Paste")
			(net "GND")
		)
		(pad "66" smd rect
			(at -2.050034 -8.074914 90)
			(size 0.519938 1.4986)
			(layers "F.Cu" "F.Mask" "F.Paste")
			(net "M_I_CPU0_SA_CA<0>")
		)
		(pad "67" smd rect
			(at -2.050034 -7.22503 90)
			(size 0.519938 1.4986)
			(layers "F.Cu" "F.Mask" "F.Paste")
			(net "GND")
		)
		(pad "68" smd rect
			(at -2.050034 -6.374892 90)
			(size 0.519938 1.4986)
			(layers "F.Cu" "F.Mask" "F.Paste")
			(net "M_I_CPU0_SA_CA<2>")
		)
		(pad "69" smd rect
			(at -2.050034 -5.525008 90)
			(size 0.519938 1.4986)
			(layers "F.Cu" "F.Mask" "F.Paste")
			(net "GND")
		)
		(pad "70" smd rect
			(at -2.050034 -4.675124 90)
			(size 0.519938 1.4986)
			(layers "F.Cu" "F.Mask" "F.Paste")
			(net "M_I_CPU0_SA_CA<4>")
		)
		(pad "71" smd rect
			(at -2.050034 -3.824986 90)
			(size 0.519938 1.4986)
			(layers "F.Cu" "F.Mask" "F.Paste")
			(net "GND")
		)
		(pad "72" smd rect
			(at -2.050034 -2.975102 90)
			(size 0.519938 1.4986)
			(layers "F.Cu" "F.Mask" "F.Paste")
			(net "M_I_CPU0_SA_CA<6>")
		)
		(pad "73" smd rect
			(at -2.050034 -2.124964 90)
			(size 0.519938 1.4986)
			(layers "F.Cu" "F.Mask" "F.Paste")
			(net "GND")
		)
		(pad "74" smd rect
			(at -2.050034 -1.27508 90)
			(size 0.519938 1.4986)
			(layers "F.Cu" "F.Mask" "F.Paste")
			(net "M_I_CPU0_SA_PAR")
		)
		(pad "75" smd rect
			(at -2.050034 -0.424942 90)
			(size 0.519938 1.4986)
			(layers "F.Cu" "F.Mask" "F.Paste")
			(net "GND")
		)
		(pad "76" smd rect
			(at -2.050034 5.525008 90)
			(size 0.519938 1.4986)
			(layers "F.Cu" "F.Mask" "F.Paste")
			(net "M_I_CPU0_SB_CA<0>")
		)
		(pad "77" smd rect
			(at -2.050034 6.374892 90)
			(size 0.519938 1.4986)
			(layers "F.Cu" "F.Mask" "F.Paste")
			(net "GND")
		)
		(pad "78" smd rect
			(at -2.050034 7.22503 90)
			(size 0.519938 1.4986)
			(layers "F.Cu" "F.Mask" "F.Paste")
			(net "M_I_CPU0_SB_CA<2>")
		)
		(pad "79" smd rect
			(at -2.050034 8.074914 90)
			(size 0.519938 1.4986)
			(layers "F.Cu" "F.Mask" "F.Paste")
			(net "GND")
		)
		(pad "80" smd rect
			(at -2.050034 8.925052 90)
			(size 0.519938 1.4986)
			(layers "F.Cu" "F.Mask" "F.Paste")
			(net "M_I_CPU0_SB_CA<4>")
		)
		(pad "81" smd rect
			(at -2.050034 9.774936 90)
			(size 0.519938 1.4986)
			(layers "F.Cu" "F.Mask" "F.Paste")
			(net "GND")
		)
		(pad "82" smd rect
			(at -2.050034 10.625074 90)
			(size 0.519938 1.4986)
			(layers "F.Cu" "F.Mask" "F.Paste")
			(net "M_I_CPU0_SB_CA<6>")
		)
		(pad "83" smd rect
			(at -2.050034 11.474958 90)
			(size 0.519938 1.4986)
			(layers "F.Cu" "F.Mask" "F.Paste")
			(net "GND")
		)
		(pad "84" smd rect
			(at -2.050034 12.325096 90)
			(size 0.519938 1.4986)
			(layers "F.Cu" "F.Mask" "F.Paste")
			(net "M_I_CPU0_SB_CS_N<0>")
		)
		(pad "85" smd rect
			(at -2.050034 13.17498 90)
			(size 0.519938 1.4986)
			(layers "F.Cu" "F.Mask" "F.Paste")
			(net "GND")
		)
		(pad "86" smd rect
			(at -2.050034 14.025118 90)
			(size 0.519938 1.4986)
			(layers "F.Cu" "F.Mask" "F.Paste")
			(net "M_I_CPU0_SA_RSP<0>")
		)
		(pad "87" smd rect
			(at -2.050034 14.875002 90)
			(size 0.519938 1.4986)
			(layers "F.Cu" "F.Mask" "F.Paste")
			(net "M_I_CPU0_SB_RSP<0>")
		)
		(pad "88" smd rect
			(at -2.050034 15.724886 90)
			(size 0.519938 1.4986)
			(layers "F.Cu" "F.Mask" "F.Paste")
			(net "GND")
		)
		(pad "89" smd rect
			(at -2.050034 16.575024 90)
			(size 0.519938 1.4986)
			(layers "F.Cu" "F.Mask" "F.Paste")
			(net "M_I_CPU0_SB_CB<4>")
		)
		(pad "90" smd rect
			(at -2.050034 17.424908 90)
			(size 0.519938 1.4986)
			(layers "F.Cu" "F.Mask" "F.Paste")
			(net "GND")
		)
		(pad "91" smd rect
			(at -2.050034 18.275046 90)
			(size 0.519938 1.4986)
			(layers "F.Cu" "F.Mask" "F.Paste")
			(net "M_I_CPU0_SB_CB<5>")
		)
		(pad "92" smd rect
			(at -2.050034 19.12493 90)
			(size 0.519938 1.4986)
			(layers "F.Cu" "F.Mask" "F.Paste")
			(net "GND")
		)
		(pad "93" smd rect
			(at -2.050034 19.975068 90)
			(size 0.519938 1.4986)
			(layers "F.Cu" "F.Mask" "F.Paste")
			(net "M_I_CPU0_SB_DQS_DP<9>")
		)
		(pad "94" smd rect
			(at -2.050034 20.824952 90)
			(size 0.519938 1.4986)
			(layers "F.Cu" "F.Mask" "F.Paste")
			(net "M_I_CPU0_SB_DQS_DN<9>")
		)
		(pad "95" smd rect
			(at -2.050034 21.67509 90)
			(size 0.519938 1.4986)
			(layers "F.Cu" "F.Mask" "F.Paste")
			(net "GND")
		)
		(pad "96" smd rect
			(at -2.050034 22.524974 90)
			(size 0.519938 1.4986)
			(layers "F.Cu" "F.Mask" "F.Paste")
			(net "M_I_CPU0_SB_CB<0>")
		)
		(pad "97" smd rect
			(at -2.050034 23.375112 90)
			(size 0.519938 1.4986)
			(layers "F.Cu" "F.Mask" "F.Paste")
			(net "GND")
		)
		(pad "98" smd rect
			(at -2.050034 24.224996 90)
			(size 0.519938 1.4986)
			(layers "F.Cu" "F.Mask" "F.Paste")
			(net "M_I_CPU0_SB_CB<1>")
		)
		(pad "99" smd rect
			(at -2.050034 25.07488 90)
			(size 0.519938 1.4986)
			(layers "F.Cu" "F.Mask" "F.Paste")
			(net "GND")
		)
		(pad "100" smd rect
			(at -2.050034 25.925018 90)
			(size 0.519938 1.4986)
			(layers "F.Cu" "F.Mask" "F.Paste")
			(net "M_I_CPU0_SB_DQ<0>")
		)
		(pad "101" smd rect
			(at -2.050034 26.774902 90)
			(size 0.519938 1.4986)
			(layers "F.Cu" "F.Mask" "F.Paste")
			(net "GND")
		)
		(pad "102" smd rect
			(at -2.050034 27.62504 90)
			(size 0.519938 1.4986)
			(layers "F.Cu" "F.Mask" "F.Paste")
			(net "M_I_CPU0_SB_DQ<1>")
		)
		(pad "103" smd rect
			(at -2.050034 28.474924 90)
			(size 0.519938 1.4986)
			(layers "F.Cu" "F.Mask" "F.Paste")
			(net "GND")
		)
		(pad "104" smd rect
			(at -2.050034 29.325062 90)
			(size 0.519938 1.4986)
			(layers "F.Cu" "F.Mask" "F.Paste")
			(net "M_I_CPU0_SB_DQS_DP<0>")
		)
		(pad "105" smd rect
			(at -2.050034 30.174946 90)
			(size 0.519938 1.4986)
			(layers "F.Cu" "F.Mask" "F.Paste")
			(net "M_I_CPU0_SB_DQS_DN<0>")
		)
		(pad "106" smd rect
			(at -2.050034 31.025084 90)
			(size 0.519938 1.4986)
			(layers "F.Cu" "F.Mask" "F.Paste")
			(net "GND")
		)
		(pad "107" smd rect
			(at -2.050034 31.874968 90)
			(size 0.519938 1.4986)
			(layers "F.Cu" "F.Mask" "F.Paste")
			(net "M_I_CPU0_SB_DQ<4>")
		)
		(pad "108" smd rect
			(at -2.050034 32.725106 90)
			(size 0.519938 1.4986)
			(layers "F.Cu" "F.Mask" "F.Paste")
			(net "GND")
		)
		(pad "109" smd rect
			(at -2.050034 33.57499 90)
			(size 0.519938 1.4986)
			(layers "F.Cu" "F.Mask" "F.Paste")
			(net "M_I_CPU0_SB_DQ<5>")
		)
		(pad "110" smd rect
			(at -2.050034 34.425128 90)
			(size 0.519938 1.4986)
			(layers "F.Cu" "F.Mask" "F.Paste")
			(net "GND")
		)
		(pad "111" smd rect
			(at -2.050034 35.275012 90)
			(size 0.519938 1.4986)
			(layers "F.Cu" "F.Mask" "F.Paste")
			(net "M_I_CPU0_SB_DQ<8>")
		)
		(pad "112" smd rect
			(at -2.050034 36.124896 90)
			(size 0.519938 1.4986)
			(layers "F.Cu" "F.Mask" "F.Paste")
			(net "GND")
		)
		(pad "113" smd rect
			(at -2.050034 36.975034 90)
			(size 0.519938 1.4986)
			(layers "F.Cu" "F.Mask" "F.Paste")
			(net "M_I_CPU0_SB_DQ<9>")
		)
	)
)
